(kicad_pcb
	(version 20260206)
	(generator "pcbnew")
	(generator_version "10.0")
	(general
		(thickness 1.6)
		(legacy_teardrops no)
	)
	(paper "A4")
	(title_block
		(title "Wiwynn_Tioga_Pass_MB.brd")
		(comment 1 "Tioga Pass / footprints 2221-2228 of 4770")
	)
	(layers
		(0 "F.Cu" signal "TOP")
		(4 "In1.Cu" signal "L2GND")
		(6 "In2.Cu" signal "L3")
		(8 "In3.Cu" signal "L4GND")
		(10 "In4.Cu" signal "L5")
		(12 "In5.Cu" signal "L6GND")
		(14 "In6.Cu" signal "L7VCC")
		(16 "In7.Cu" signal "L8VCC")
		(18 "In8.Cu" signal "L9GND")
		(20 "In9.Cu" signal "L10")
		(22 "In10.Cu" signal "L11GND")
		(24 "In11.Cu" signal "L12")
		(26 "In12.Cu" signal "L13GND")
		(2 "B.Cu" signal "BOTTOM")
		(9 "F.Adhes" user "F.Adhesive")
		(11 "B.Adhes" user "B.Adhesive")
		(13 "F.Paste" user "Package Geometry/Pastemask Top")
		(15 "B.Paste" user "Package Geometry/Pastemask Bottom")
		(5 "F.SilkS" user "Ref Des/Silkscreen Top")
		(7 "B.SilkS" user "Ref Des/Silkscreen Bottom")
		(1 "F.Mask" user "Board Geometry/Soldermask Top")
		(3 "B.Mask" user "Board Geometry/Soldermask Bottom")
		(17 "Dwgs.User" user "User.Drawings")
		(19 "Cmts.User" user "User.Comments")
		(21 "Eco1.User" user "User.Eco1")
		(23 "Eco2.User" user "User.Eco2")
		(25 "Edge.Cuts" user "Board Geometry/Outline")
		(27 "Margin" user)
		(31 "F.CrtYd" user "Package Geometry/Place Bound Top")
		(29 "B.CrtYd" user "Package Geometry/Place Bound Bottom")
		(35 "F.Fab" user "Ref Des/Assembly Top")
		(33 "B.Fab" user "Ref Des/Assembly Bottom")
	)
	(footprint ""
		(layer "F.Cu")
		(at 391.795 -155.067 -90)
		(property "Reference" "R8A2"
			(at 0 0 270)
			(layer "F.SilkS")
			(hide yes)
			(effects
				(font
					(size 1.27 1.27)
				)
			)
		)
		(property "Value" ""
			(at 0 0 270)
			(layer "F.Fab")
			(effects
				(font
					(size 1.27 1.27)
				)
			)
		)
		(duplicate_pad_numbers_are_jumpers no)
		(fp_poly
			(pts
				(xy -0.2794 -0.1016) (xy 0.2794 -0.1016) (xy 0.2794 0.9906) (xy -0.2794 0.9906)
			)
			(stroke
				(width 0)
				(type default)
			)
			(fill no)
			(layer "F.CrtYd")
		)
		(fp_line
			(start -0.2794 0.9906)
			(end 0.2794 0.9906)
			(stroke
				(width 0.1)
				(type default)
			)
			(layer "F.Fab")
		)
		(fp_line
			(start 0.2794 0.9906)
			(end 0.2794 -0.1016)
			(stroke
				(width 0.1)
				(type default)
			)
			(layer "F.Fab")
		)
		(fp_line
			(start -0.2794 -0.1016)
			(end -0.2794 0.9906)
			(stroke
				(width 0.1)
				(type default)
			)
			(layer "F.Fab")
		)
		(fp_line
			(start 0.2794 -0.1016)
			(end -0.2794 -0.1016)
			(stroke
				(width 0.1)
				(type default)
			)
			(layer "F.Fab")
		)
		(pad "1" smd rect
			(at 0 0 270)
			(size 0.508 0.508)
			(layers "F.Cu" "F.Mask" "F.Paste")
			(net "VR_PVNN_PCH_XADDR2")
		)
		(pad "2" smd rect
			(at 0 0.889 270)
			(size 0.508 0.508)
			(layers "F.Cu" "F.Mask" "F.Paste")
			(net "GND")
		)
		(zone
			(layer "F.Cu")
			(hatch none 0.5)
			(connect_pads
				(clearance 0)
			)
			(min_thickness 0.25)
			(keepout
				(tracks not_allowed)
				(vias allowed)
				(pads allowed)
				(copperpour not_allowed)
				(footprints allowed)
			)
			(placement
				(enabled no)
				(sheetname "")
			)
			(fill
				(thermal_gap 0.5)
				(thermal_bridge_width 0.5)
				(island_removal_mode 0)
			)
			(polygon
				(pts
					(xy 391.16 -155.321) (xy 391.16 -154.813) (xy 391.541 -154.813) (xy 391.541 -155.321)
				)
			)
		)
		(zone
			(layer "F.Cu")
			(hatch none 0.5)
			(connect_pads
				(clearance 0)
			)
			(min_thickness 0.25)
			(keepout
				(tracks allowed)
				(vias not_allowed)
				(pads allowed)
				(copperpour not_allowed)
				(footprints allowed)
			)
			(placement
				(enabled no)
				(sheetname "")
			)
			(fill
				(thermal_gap 0.5)
				(thermal_bridge_width 0.5)
				(island_removal_mode 0)
			)
			(polygon
				(pts
					(xy 391.541 -155.321) (xy 391.541 -154.813) (xy 391.16 -154.813) (xy 391.16 -155.321)
				)
			)
		)
	)
	(footprint ""
		(layer "F.Cu")
		(at 388.8232 -0.254)
		(property "Reference" "R7G19"
			(at 0 0 0)
			(layer "F.SilkS")
			(hide yes)
			(effects
				(font
					(size 1.27 1.27)
				)
			)
		)
		(property "Value" ""
			(at 0 0 0)
			(layer "F.Fab")
			(effects
				(font
					(size 1.27 1.27)
				)
			)
		)
		(duplicate_pad_numbers_are_jumpers no)
		(fp_poly
			(pts
				(xy -0.2794 -0.1016) (xy 0.2794 -0.1016) (xy 0.2794 0.9906) (xy -0.2794 0.9906)
			)
			(stroke
				(width 0)
				(type default)
			)
			(fill no)
			(layer "F.CrtYd")
		)
		(fp_line
			(start -0.2794 -0.1016)
			(end -0.2794 0.9906)
			(stroke
				(width 0.1)
				(type default)
			)
			(layer "F.Fab")
		)
		(fp_line
			(start -0.2794 0.9906)
			(end 0.2794 0.9906)
			(stroke
				(width 0.1)
				(type default)
			)
			(layer "F.Fab")
		)
		(fp_line
			(start 0.2794 -0.1016)
			(end -0.2794 -0.1016)
			(stroke
				(width 0.1)
				(type default)
			)
			(layer "F.Fab")
		)
		(fp_line
			(start 0.2794 0.9906)
			(end 0.2794 -0.1016)
			(stroke
				(width 0.1)
				(type default)
			)
			(layer "F.Fab")
		)
		(pad "1" smd rect
			(at 0 0)
			(size 0.508 0.508)
			(layers "F.Cu" "F.Mask" "F.Paste")
			(net "JTAG_PCH_GBE_TDI")
		)
		(pad "2" smd rect
			(at 0 0.889)
			(size 0.508 0.508)
			(layers "F.Cu" "F.Mask" "F.Paste")
			(net "JTAG_TDI")
		)
		(zone
			(layer "F.Cu")
			(hatch none 0.5)
			(connect_pads
				(clearance 0)
			)
			(min_thickness 0.25)
			(keepout
				(tracks allowed)
				(vias not_allowed)
				(pads allowed)
				(copperpour not_allowed)
				(footprints allowed)
			)
			(placement
				(enabled no)
				(sheetname "")
			)
			(fill
				(thermal_gap 0.5)
				(thermal_bridge_width 0.5)
				(island_removal_mode 0)
			)
			(polygon
				(pts
					(xy 388.5692 0) (xy 389.0772 0) (xy 389.0772 0.381) (xy 388.5692 0.381)
				)
			)
		)
		(zone
			(layer "F.Cu")
			(hatch none 0.5)
			(connect_pads
				(clearance 0)
			)
			(min_thickness 0.25)
			(keepout
				(tracks not_allowed)
				(vias allowed)
				(pads allowed)
				(copperpour not_allowed)
				(footprints allowed)
			)
			(placement
				(enabled no)
				(sheetname "")
			)
			(fill
				(thermal_gap 0.5)
				(thermal_bridge_width 0.5)
				(island_removal_mode 0)
			)
			(polygon
				(pts
					(xy 388.5692 0.381) (xy 389.0772 0.381) (xy 389.0772 0) (xy 388.5692 0)
				)
			)
		)
	)
	(footprint ""
		(layer "F.Cu")
		(at 176.037494 -58.982356)
		(property "Reference" "C22W19"
			(at 0 0 0)
			(layer "F.SilkS")
			(hide yes)
			(effects
				(font
					(size 1.27 1.27)
				)
			)
		)
		(property "Value" "*"
			(at -0.0762 -6.2357 0)
			(unlocked yes)
			(layer "F.Fab")
			(hide yes)
			(effects
				(font
					(size 1.27 1.016)
					(thickness 0.1524)
				)
			)
		)
		(property "Device Type" "SC22U16V5MX-4-GP_SMD-BCG5-SC22A"
			(at -0.0762 -8.2677 0)
			(unlocked yes)
			(layer "F.Fab")
			(hide yes)
			(effects
				(font
					(size 1.27 1.016)
					(thickness 0.1524)
				)
			)
		)
		(duplicate_pad_numbers_are_jumpers no)
		(fp_line
			(start 0.635 0)
			(end -0.635 0)
			(stroke
				(width 0.508)
				(type default)
			)
			(layer "F.SilkS")
		)
		(fp_rect
			(start -0.9652 1.778)
			(end 0.9652 -1.778)
			(stroke
				(width 0)
				(type default)
			)
			(fill no)
			(layer "F.CrtYd")
		)
		(fp_poly
			(pts
				(xy -0.9652 -1.778) (xy 0.9652 -1.778) (xy 0.9652 1.778) (xy -0.9652 1.778)
			)
			(stroke
				(width 0)
				(type default)
			)
			(fill no)
			(layer "F.Fab")
		)
		(pad "1" smd rect
			(at 0 -0.9652)
			(size 1.397 1.143)
			(layers "F.Cu" "F.Mask" "F.Paste")
			(net "VR_FET_SW_P12V_STBY_PVCCIN_CPU0")
		)
		(pad "2" smd rect
			(at 0 0.9652)
			(size 1.397 1.143)
			(layers "F.Cu" "F.Mask" "F.Paste")
			(net "GND")
		)
	)
	(footprint ""
		(layer "F.Cu")
		(at 338.836 -18.161 -90)
		(property "Reference" "R12W26"
			(at -0.8382 -0.67818 270)
			(unlocked yes)
			(layer "F.SilkS")
			(effects
				(font
					(size 0.4064 0.254)
					(thickness 0.1524)
				)
				(justify left)
			)
		)
		(property "Value" ""
			(at 0 0 270)
			(layer "F.Fab")
			(effects
				(font
					(size 1.27 1.27)
				)
			)
		)
		(duplicate_pad_numbers_are_jumpers no)
		(fp_poly
			(pts
				(xy -0.2794 -0.1016) (xy 0.2794 -0.1016) (xy 0.2794 0.9906) (xy -0.2794 0.9906)
			)
			(stroke
				(width 0)
				(type default)
			)
			(fill no)
			(layer "F.CrtYd")
		)
		(fp_line
			(start -0.2794 0.9906)
			(end 0.2794 0.9906)
			(stroke
				(width 0.1)
				(type default)
			)
			(layer "F.Fab")
		)
		(fp_line
			(start 0.2794 0.9906)
			(end 0.2794 -0.1016)
			(stroke
				(width 0.1)
				(type default)
			)
			(layer "F.Fab")
		)
		(fp_line
			(start -0.2794 -0.1016)
			(end -0.2794 0.9906)
			(stroke
				(width 0.1)
				(type default)
			)
			(layer "F.Fab")
		)
		(fp_line
			(start 0.2794 -0.1016)
			(end -0.2794 -0.1016)
			(stroke
				(width 0.1)
				(type default)
			)
			(layer "F.Fab")
		)
		(pad "1" smd rect
			(at 0 0 270)
			(size 0.508 0.508)
			(layers "F.Cu" "F.Mask" "F.Paste")
			(net "TP_PVDDQ_ABC_MP1")
		)
		(pad "2" smd rect
			(at 0 0.889 270)
			(size 0.508 0.508)
			(layers "F.Cu" "F.Mask" "F.Paste")
			(net "PWRGD_PVDDQ_ABC")
		)
		(zone
			(layer "F.Cu")
			(hatch none 0.5)
			(connect_pads
				(clearance 0)
			)
			(min_thickness 0.25)
			(keepout
				(tracks not_allowed)
				(vias allowed)
				(pads allowed)
				(copperpour not_allowed)
				(footprints allowed)
			)
			(placement
				(enabled no)
				(sheetname "")
			)
			(fill
				(thermal_gap 0.5)
				(thermal_bridge_width 0.5)
				(island_removal_mode 0)
			)
			(polygon
				(pts
					(xy 338.201 -18.415) (xy 338.201 -17.907) (xy 338.582 -17.907) (xy 338.582 -18.415)
				)
			)
		)
		(zone
			(layer "F.Cu")
			(hatch none 0.5)
			(connect_pads
				(clearance 0)
			)
			(min_thickness 0.25)
			(keepout
				(tracks allowed)
				(vias not_allowed)
				(pads allowed)
				(copperpour not_allowed)
				(footprints allowed)
			)
			(placement
				(enabled no)
				(sheetname "")
			)
			(fill
				(thermal_gap 0.5)
				(thermal_bridge_width 0.5)
				(island_removal_mode 0)
			)
			(polygon
				(pts
					(xy 338.582 -18.415) (xy 338.582 -17.907) (xy 338.201 -17.907) (xy 338.201 -18.415)
				)
			)
		)
	)
	(footprint ""
		(layer "F.Cu")
		(at 377.5202 -29.232352 90)
		(property "Reference" "C8F13"
			(at -0.8382 -0.67818 90)
			(unlocked yes)
			(layer "F.SilkS")
			(effects
				(font
					(size 0.4064 0.254)
					(thickness 0.1524)
				)
				(justify left)
			)
		)
		(property "Value" ""
			(at 0 0 90)
			(layer "F.Fab")
			(effects
				(font
					(size 1.27 1.27)
				)
			)
		)
		(duplicate_pad_numbers_are_jumpers no)
		(fp_poly
			(pts
				(xy 0.3048 -0.1016) (xy 0.3048 0.9906) (xy -0.3048 0.9906) (xy -0.3048 -0.1016)
			)
			(stroke
				(width 0)
				(type default)
			)
			(fill no)
			(layer "F.CrtYd")
		)
		(fp_line
			(start 0.3048 -0.1016)
			(end -0.3048 -0.1016)
			(stroke
				(width 0.1)
				(type default)
			)
			(layer "F.Fab")
		)
		(fp_line
			(start -0.3048 -0.1016)
			(end -0.3048 0.9906)
			(stroke
				(width 0.1)
				(type default)
			)
			(layer "F.Fab")
		)
		(fp_line
			(start 0.3048 0.9906)
			(end 0.3048 -0.1016)
			(stroke
				(width 0.1)
				(type default)
			)
			(layer "F.Fab")
		)
		(fp_line
			(start -0.3048 0.9906)
			(end 0.3048 0.9906)
			(stroke
				(width 0.1)
				(type default)
			)
			(layer "F.Fab")
		)
		(pad "1" smd rect
			(at 0 0 90)
			(size 0.508 0.508)
			(layers "F.Cu" "F.Mask" "F.Paste")
			(net "SATA6G_S0_RX_DP")
		)
		(pad "2" smd rect
			(at 0 0.889 90)
			(size 0.508 0.508)
			(layers "F.Cu" "F.Mask" "F.Paste")
			(net "P3E_PCH_M2_SATA6G_RX_R_DP")
		)
		(zone
			(layer "F.Cu")
			(hatch none 0.5)
			(connect_pads
				(clearance 0)
			)
			(min_thickness 0.25)
			(keepout
				(tracks allowed)
				(vias not_allowed)
				(pads allowed)
				(copperpour not_allowed)
				(footprints allowed)
			)
			(placement
				(enabled no)
				(sheetname "")
			)
			(fill
				(thermal_gap 0.5)
				(thermal_bridge_width 0.5)
				(island_removal_mode 0)
			)
			(polygon
				(pts
					(xy 377.7742 -28.978352) (xy 377.7742 -29.486352) (xy 378.1552 -29.486352) (xy 378.1552 -28.978352)
				)
			)
		)
		(zone
			(layer "F.Cu")
			(hatch none 0.5)
			(connect_pads
				(clearance 0)
			)
			(min_thickness 0.25)
			(keepout
				(tracks not_allowed)
				(vias allowed)
				(pads allowed)
				(copperpour not_allowed)
				(footprints allowed)
			)
			(placement
				(enabled no)
				(sheetname "")
			)
			(fill
				(thermal_gap 0.5)
				(thermal_bridge_width 0.5)
				(island_removal_mode 0)
			)
			(polygon
				(pts
					(xy 378.1552 -28.978352) (xy 378.1552 -29.486352) (xy 377.7742 -29.486352) (xy 377.7742 -28.978352)
				)
			)
		)
	)
	(footprint ""
		(layer "F.Cu")
		(at 32.667194 -102.285292 90)
		(property "Reference" "C1C15"
			(at 0 0 90)
			(layer "F.SilkS")
			(hide yes)
			(effects
				(font
					(size 1.27 1.27)
				)
			)
		)
		(property "Value" ""
			(at 0 0 90)
			(layer "F.Fab")
			(effects
				(font
					(size 1.27 1.27)
				)
			)
		)
		(duplicate_pad_numbers_are_jumpers no)
		(fp_rect
			(start 0.3048 -0.1016)
			(end -0.3048 0.9906)
			(stroke
				(width 0)
				(type default)
			)
			(fill no)
			(layer "F.CrtYd")
		)
		(fp_line
			(start 0.3048 -0.1016)
			(end -0.3048 -0.1016)
			(stroke
				(width 0.1)
				(type default)
			)
			(layer "F.Fab")
		)
		(fp_line
			(start -0.3048 -0.1016)
			(end -0.3048 0.9906)
			(stroke
				(width 0.1)
				(type default)
			)
			(layer "F.Fab")
		)
		(fp_line
			(start 0.3048 0.9906)
			(end 0.3048 -0.1016)
			(stroke
				(width 0.1)
				(type default)
			)
			(layer "F.Fab")
		)
		(fp_line
			(start -0.3048 0.9906)
			(end 0.3048 0.9906)
			(stroke
				(width 0.1)
				(type default)
			)
			(layer "F.Fab")
		)
		(pad "1" smd rect
			(at 0 0 90)
			(size 0.508 0.508)
			(layers "F.Cu" "F.Mask" "F.Paste")
			(net "VR_FET_SW_P12V_STBY_PVCCIN_CPU1")
		)
		(pad "2" smd rect
			(at 0 0.889 90)
			(size 0.508 0.508)
			(layers "F.Cu" "F.Mask" "F.Paste")
			(net "GND")
		)
		(zone
			(layer "F.Cu")
			(hatch none 0.5)
			(connect_pads
				(clearance 0)
			)
			(min_thickness 0.25)
			(keepout
				(tracks allowed)
				(vias not_allowed)
				(pads allowed)
				(copperpour not_allowed)
				(footprints allowed)
			)
			(placement
				(enabled no)
				(sheetname "")
			)
			(fill
				(thermal_gap 0.5)
				(thermal_bridge_width 0.5)
				(island_removal_mode 0)
			)
			(polygon
				(pts
					(xy 32.921194 -102.539292) (xy 32.921194 -102.031292) (xy 33.302194 -102.031292) (xy 33.302194 -102.539292)
				)
			)
		)
		(zone
			(layer "F.Cu")
			(hatch none 0.5)
			(connect_pads
				(clearance 0)
			)
			(min_thickness 0.25)
			(keepout
				(tracks not_allowed)
				(vias allowed)
				(pads allowed)
				(copperpour not_allowed)
				(footprints allowed)
			)
			(placement
				(enabled no)
				(sheetname "")
			)
			(fill
				(thermal_gap 0.5)
				(thermal_bridge_width 0.5)
				(island_removal_mode 0)
			)
			(polygon
				(pts
					(xy 32.921194 -102.539292) (xy 32.921194 -102.031292) (xy 33.302194 -102.031292) (xy 33.302194 -102.539292)
				)
			)
		)
	)
	(footprint ""
		(layer "F.Cu")
		(at 336.2706 -129.0955)
		(property "Reference" "R7B11"
			(at 0 0 0)
			(layer "F.SilkS")
			(hide yes)
			(effects
				(font
					(size 1.27 1.27)
				)
			)
		)
		(property "Value" ""
			(at 0 0 0)
			(layer "F.Fab")
			(effects
				(font
					(size 1.27 1.27)
				)
			)
		)
		(duplicate_pad_numbers_are_jumpers no)
		(fp_poly
			(pts
				(xy -0.2794 -0.1016) (xy 0.2794 -0.1016) (xy 0.2794 0.9906) (xy -0.2794 0.9906)
			)
			(stroke
				(width 0)
				(type default)
			)
			(fill no)
			(layer "F.CrtYd")
		)
		(fp_line
			(start -0.2794 -0.1016)
			(end -0.2794 0.9906)
			(stroke
				(width 0.1)
				(type default)
			)
			(layer "F.Fab")
		)
		(fp_line
			(start -0.2794 0.9906)
			(end 0.2794 0.9906)
			(stroke
				(width 0.1)
				(type default)
			)
			(layer "F.Fab")
		)
		(fp_line
			(start 0.2794 -0.1016)
			(end -0.2794 -0.1016)
			(stroke
				(width 0.1)
				(type default)
			)
			(layer "F.Fab")
		)
		(fp_line
			(start 0.2794 0.9906)
			(end 0.2794 -0.1016)
			(stroke
				(width 0.1)
				(type default)
			)
			(layer "F.Fab")
		)
		(pad "1" smd rect
			(at 0 0)
			(size 0.508 0.508)
			(layers "F.Cu" "F.Mask" "F.Paste")
			(net "PVPP_DEF")
		)
		(pad "2" smd rect
			(at 0 0.889)
			(size 0.508 0.508)
			(layers "F.Cu" "F.Mask" "F.Paste")
			(net "VSENSE_PVPP_DEF")
		)
		(zone
			(layer "F.Cu")
			(hatch none 0.5)
			(connect_pads
				(clearance 0)
			)
			(min_thickness 0.25)
			(keepout
				(tracks allowed)
				(vias not_allowed)
				(pads allowed)
				(copperpour not_allowed)
				(footprints allowed)
			)
			(placement
				(enabled no)
				(sheetname "")
			)
			(fill
				(thermal_gap 0.5)
				(thermal_bridge_width 0.5)
				(island_removal_mode 0)
			)
			(polygon
				(pts
					(xy 336.0166 -128.8415) (xy 336.5246 -128.8415) (xy 336.5246 -128.4605) (xy 336.0166 -128.4605)
				)
			)
		)
		(zone
			(layer "F.Cu")
			(hatch none 0.5)
			(connect_pads
				(clearance 0)
			)
			(min_thickness 0.25)
			(keepout
				(tracks not_allowed)
				(vias allowed)
				(pads allowed)
				(copperpour not_allowed)
				(footprints allowed)
			)
			(placement
				(enabled no)
				(sheetname "")
			)
			(fill
				(thermal_gap 0.5)
				(thermal_bridge_width 0.5)
				(island_removal_mode 0)
			)
			(polygon
				(pts
					(xy 336.0166 -128.4605) (xy 336.5246 -128.4605) (xy 336.5246 -128.8415) (xy 336.0166 -128.8415)
				)
			)
		)
	)
	(footprint ""
		(layer "F.Cu")
		(at 194.749928 -75.954382 -90)
		(property "Reference" "C4D30"
			(at 0 0 270)
			(layer "F.SilkS")
			(hide yes)
			(effects
				(font
					(size 1.27 1.27)
				)
			)
		)
		(property "Value" ""
			(at 0 0 270)
			(layer "F.Fab")
			(effects
				(font
					(size 1.27 1.27)
				)
			)
		)
		(duplicate_pad_numbers_are_jumpers no)
		(fp_poly
			(pts
				(xy 0.3048 -0.1016) (xy 0.3048 0.9906) (xy -0.3048 0.9906) (xy -0.3048 -0.1016)
			)
			(stroke
				(width 0)
				(type default)
			)
			(fill no)
			(layer "F.CrtYd")
		)
		(fp_line
			(start -0.3048 0.9906)
			(end 0.3048 0.9906)
			(stroke
				(width 0.1)
				(type default)
			)
			(layer "F.Fab")
		)
		(fp_line
			(start 0.3048 0.9906)
			(end 0.3048 -0.1016)
			(stroke
				(width 0.1)
				(type default)
			)
			(layer "F.Fab")
		)
		(fp_line
			(start -0.3048 -0.1016)
			(end -0.3048 0.9906)
			(stroke
				(width 0.1)
				(type default)
			)
			(layer "F.Fab")
		)
		(fp_line
			(start 0.3048 -0.1016)
			(end -0.3048 -0.1016)
			(stroke
				(width 0.1)
				(type default)
			)
			(layer "F.Fab")
		)
		(pad "1" smd rect
			(at 0 0 270)
			(size 0.508 0.508)
			(layers "F.Cu" "F.Mask" "F.Paste")
			(net "VR_FET_SW_P12V_STBY_PVCCIN_CPU0")
		)
		(pad "2" smd rect
			(at 0 0.889 270)
			(size 0.508 0.508)
			(layers "F.Cu" "F.Mask" "F.Paste")
			(net "GND")
		)
		(zone
			(layer "F.Cu")
			(hatch none 0.5)
			(connect_pads
				(clearance 0)
			)
			(min_thickness 0.25)
			(keepout
				(tracks not_allowed)
				(vias allowed)
				(pads allowed)
				(copperpour not_allowed)
				(footprints allowed)
			)
			(placement
				(enabled no)
				(sheetname "")
			)
			(fill
				(thermal_gap 0.5)
				(thermal_bridge_width 0.5)
				(island_removal_mode 0)
			)
			(polygon
				(pts
					(xy 194.114928 -76.208382) (xy 194.114928 -75.700382) (xy 194.495928 -75.700382) (xy 194.495928 -76.208382)
				)
			)
		)
		(zone
			(layer "F.Cu")
			(hatch none 0.5)
			(connect_pads
				(clearance 0)
			)
			(min_thickness 0.25)
			(keepout
				(tracks allowed)
				(vias not_allowed)
				(pads allowed)
				(copperpour not_allowed)
				(footprints allowed)
			)
			(placement
				(enabled no)
				(sheetname "")
			)
			(fill
				(thermal_gap 0.5)
				(thermal_bridge_width 0.5)
				(island_removal_mode 0)
			)
			(polygon
				(pts
					(xy 194.495928 -76.208382) (xy 194.495928 -75.700382) (xy 194.114928 -75.700382) (xy 194.114928 -76.208382)
				)
			)
		)
	)
)
